(kicad_pcb
	(version 20260206)
	(generator "pcbnew")
	(generator_version "10.0")
	(general
		(thickness 1.6)
		(legacy_teardrops no)
	)
	(paper "A4")
	(title_block
		(title "v2-tray-backplane — ms_tbp_v2.brd")
		(comment 1 "Open CloudServer (Microsoft) / footprints 155-157 of 164")
	)
	(layers
		(0 "F.Cu" signal "TOP")
		(4 "In1.Cu" signal "LYR2")
		(6 "In2.Cu" signal "LYR3")
		(8 "In3.Cu" signal "LYR4")
		(10 "In4.Cu" signal "LYR5")
		(12 "In5.Cu" signal "LYR6")
		(14 "In6.Cu" signal "LYR7")
		(2 "B.Cu" signal "BOTTOM")
		(9 "F.Adhes" user "F.Adhesive")
		(11 "B.Adhes" user "B.Adhesive")
		(13 "F.Paste" user "Package Geometry/Pastemask Top")
		(15 "B.Paste" user "Package Geometry/Pastemask Bottom")
		(5 "F.SilkS" user "Ref Des/Silkscreen Top")
		(7 "B.SilkS" user "Ref Des/Silkscreen Bottom")
		(1 "F.Mask" user "Board Geometry/Soldermask Top")
		(3 "B.Mask" user "Board Geometry/Soldermask Bottom")
		(17 "Dwgs.User" user "User.Drawings")
		(19 "Cmts.User" user "User.Comments")
		(21 "Eco1.User" user "User.Eco1")
		(23 "Eco2.User" user "User.Eco2")
		(25 "Edge.Cuts" user "Board Geometry/Outline")
		(27 "Margin" user)
		(31 "F.CrtYd" user "Package Geometry/Place Bound Top")
		(29 "B.CrtYd" user "Package Geometry/Place Bound Bottom")
		(35 "F.Fab" user "Ref Des/Assembly Top")
		(33 "B.Fab" user "Ref Des/Assembly Bottom")
	)
	(footprint ""
		(layer "F.Cu")
		(at -300.9392 7.4676)
		(property "Reference" "R4"
			(at -3.6068 -0.0635 0)
			(unlocked yes)
			(layer "F.SilkS")
			(effects
				(font
					(size 0.762 0.5334)
					(thickness 0.1016)
				)
			)
		)
		(property "Value" ""
			(at 0 0 0)
			(layer "F.Fab")
			(effects
				(font
					(size 1.27 1.27)
				)
			)
		)
		(duplicate_pad_numbers_are_jumpers no)
		(fp_line
			(start 0 -0.381)
			(end 0 0.381)
			(stroke
				(width 0.127)
				(type default)
			)
			(layer "F.SilkS")
		)
		(fp_poly
			(pts
				(xy 1.255601 0.6564) (xy -1.255601 0.6564) (xy -1.255601 -0.656399) (xy 1.255601 -0.656399)
			)
			(stroke
				(width 0)
				(type default)
			)
			(fill no)
			(layer "F.CrtYd")
		)
		(fp_line
			(start -0.800001 -0.399999)
			(end -0.800001 0.399999)
			(stroke
				(width 0.1)
				(type default)
			)
			(layer "F.Fab")
		)
		(fp_line
			(start -0.800001 0.399999)
			(end 0.800001 0.399999)
			(stroke
				(width 0.1)
				(type default)
			)
			(layer "F.Fab")
		)
		(fp_line
			(start 0.800001 -0.399999)
			(end -0.800001 -0.399999)
			(stroke
				(width 0.1)
				(type default)
			)
			(layer "F.Fab")
		)
		(fp_line
			(start 0.800001 0.399999)
			(end 0.800001 -0.399999)
			(stroke
				(width 0.1)
				(type default)
			)
			(layer "F.Fab")
		)
		(pad "1" smd rect
			(at -0.650001 0)
			(size 0.7112 0.8128)
			(layers "F.Cu" "F.Mask" "F.Paste")
			(net "P3V3_B1_QSFP")
		)
		(pad "2" smd rect
			(at 0.650001 0 180)
			(size 0.7112 0.8128)
			(layers "F.Cu" "F.Mask" "F.Paste")
			(net "SKU_B1_ID1")
		)
	)
	(footprint ""
		(layer "F.Cu")
		(at -282.750001 32.059999 180)
		(property "Reference" "J6"
			(at -6.979661 -7.170301 0)
			(unlocked yes)
			(layer "F.SilkS")
			(effects
				(font
					(size 0.762 0.5334)
					(thickness 0.1016)
				)
			)
		)
		(property "Value" ""
			(at 0 0 180)
			(layer "F.Fab")
			(effects
				(font
					(size 1.27 1.27)
				)
			)
		)
		(duplicate_pad_numbers_are_jumpers no)
		(fp_line
			(start 8.099999 42.399999)
			(end 8.099999 27.999999)
			(stroke
				(width 0.127)
				(type default)
			)
			(layer "F.SilkS")
		)
		(fp_line
			(start 8.099999 23.099999)
			(end 8.099999 17.999999)
			(stroke
				(width 0.127)
				(type default)
			)
			(layer "F.SilkS")
		)
		(fp_line
			(start 8.099999 13.8)
			(end 8.099999 7.899999)
			(stroke
				(width 0.127)
				(type default)
			)
			(layer "F.SilkS")
		)
		(fp_line
			(start 8.099999 4.199999)
			(end 8.099999 -2.400001)
			(stroke
				(width 0.127)
				(type default)
			)
			(layer "F.SilkS")
		)
		(fp_line
			(start 8.099999 -5.699999)
			(end 8.099999 -6.3)
			(stroke
				(width 0.127)
				(type default)
			)
			(layer "F.SilkS")
		)
		(fp_line
			(start 8.099999 -6.3)
			(end 6.000001 -6.3)
			(stroke
				(width 0.127)
				(type default)
			)
			(layer "F.SilkS")
		)
		(fp_line
			(start -6.000001 -6.3)
			(end -8.099999 -6.3)
			(stroke
				(width 0.127)
				(type default)
			)
			(layer "F.SilkS")
		)
		(fp_line
			(start -8.099999 42.399999)
			(end 8.099999 42.399999)
			(stroke
				(width 0.127)
				(type default)
			)
			(layer "F.SilkS")
		)
		(fp_line
			(start -8.099999 32.8)
			(end -8.099999 42.399999)
			(stroke
				(width 0.127)
				(type default)
			)
			(layer "F.SilkS")
		)
		(fp_line
			(start -8.099999 22.999999)
			(end -8.099999 28.9)
			(stroke
				(width 0.127)
				(type default)
			)
			(layer "F.SilkS")
		)
		(fp_line
			(start -8.099999 12.999999)
			(end -8.099999 18.600001)
			(stroke
				(width 0.127)
				(type default)
			)
			(layer "F.SilkS")
		)
		(fp_line
			(start -8.099999 2.5)
			(end -8.099999 9.099999)
			(stroke
				(width 0.127)
				(type default)
			)
			(layer "F.SilkS")
		)
		(fp_line
			(start -8.099999 -6.3)
			(end -8.099999 -0.700002)
			(stroke
				(width 0.127)
				(type default)
			)
			(layer "F.SilkS")
		)
		(fp_poly
			(pts
				(arc
					(start 5.2054 34.950301)
					(mid 3.459364 36.043267)
					(end 1.434201 36.42)
				)
				(arc
					(start -7.124799 36.42)
					(mid -11.028153 34.803295)
					(end -12.644999 30.899999)
				)
				(xy -12.6495 30.899999) (xy -12.6495 0.9)
				(arc
					(start -12.644999 0.9)
					(mid -12.630104 0.494905)
					(end -12.585499 0.091998)
				)
				(arc
					(start -12.368601 -1.986699)
					(mid -12.153073 -3.137304)
					(end -11.6883 -4.211701)
				)
				(arc
					(start -9.541 -8.473202)
					(mid -7.601128 -10.649547)
					(end -4.800001 -11.457801)
				)
				(arc
					(start 4.8 -11.457801)
					(mid 6.526795 -11.166136)
					(end 8.062001 -10.3235)
				)
				(arc
					(start 10.390299 -8.5507)
					(mid 12.049188 -6.594625)
					(end 12.644999 -4.1)
				)
				(xy 12.6495 -4.1) (xy 12.6495 25.899999)
				(arc
					(start 12.644999 25.899999)
					(mid 12.153739 28.176398)
					(end 10.7674 30.0476)
				)
			)
			(stroke
				(width 0)
				(type default)
			)
			(fill no)
			(layer "B.CrtYd")
		)
		(fp_poly
			(pts
				(xy 9.1 43.399999) (xy -9.1 43.399999) (xy -9.1 -7.9) (xy 9.1 -7.9)
			)
			(stroke
				(width 0)
				(type default)
			)
			(fill no)
			(layer "F.CrtYd")
		)
		(fp_line
			(start 8.099999 42.399999)
			(end -8.099999 42.399999)
			(stroke
				(width 0.1)
				(type default)
			)
			(layer "F.Fab")
		)
		(fp_line
			(start 8.099999 -6.32)
			(end 8.099999 42.399999)
			(stroke
				(width 0.1)
				(type default)
			)
			(layer "F.Fab")
		)
		(fp_line
			(start -8.099999 42.399999)
			(end -8.099999 -6.32)
			(stroke
				(width 0.1)
				(type default)
			)
			(layer "F.Fab")
		)
		(fp_line
			(start -8.099999 -6.32)
			(end 8.099999 -6.32)
			(stroke
				(width 0.1)
				(type default)
			)
			(layer "F.Fab")
		)
		(pad "1" thru_hole circle
			(at 0 -6.2 180)
			(size 1.4732 1.4732)
			(drill 0.9652)
			(layers "*.Cu" "*.Mask")
			(remove_unused_layers no)
			(net "GND")
		)
		(pad "2" thru_hole circle
			(at -4.800001 -6.2 180)
			(size 1.4732 1.4732)
			(drill 0.9652)
			(layers "*.Cu" "*.Mask")
			(remove_unused_layers no)
			(net "GND")
		)
		(pad "3" thru_hole circle
			(at 4.800001 -6.2 180)
			(size 1.4732 1.4732)
			(drill 0.9652)
			(layers "*.Cu" "*.Mask")
			(remove_unused_layers no)
			(net "GND")
		)
		(pad "4" thru_hole rect
			(at 7.125 -4.099999 180)
			(size 2.0066 2.0066)
			(drill 1.0414)
			(layers "*.Cu" "*.Mask")
			(remove_unused_layers no)
			(net "GND")
			(padstack
				(mode front_inner_back)
				(layer "Inner"
					(shape circle)
					(size 2.0066 2.0066)
				)
				(layer "B.Cu"
					(shape rect)
					(size 2.0066 2.0066)
				)
			)
		)
		(pad "5" thru_hole circle
			(at -7.125 -1.599999 180)
			(size 1.4732 1.4732)
			(drill 0.9652)
			(layers "*.Cu" "*.Mask")
			(remove_unused_layers no)
			(net "GND")
		)
		(pad "6" thru_hole circle
			(at 7.125 -1.599999 180)
			(size 1.4732 1.4732)
			(drill 0.9652)
			(layers "*.Cu" "*.Mask")
			(remove_unused_layers no)
			(net "GND")
		)
		(pad "7" thru_hole rect
			(at -7.125 0.900001 180)
			(size 2.0066 2.0066)
			(drill 0.8382)
			(layers "*.Cu" "*.Mask")
			(remove_unused_layers no)
			(net "GND")
			(padstack
				(mode front_inner_back)
				(layer "Inner"
					(shape circle)
					(size 2.0066 2.0066)
				)
				(layer "B.Cu"
					(shape rect)
					(size 2.0066 2.0066)
				)
			)
		)
		(pad "8" thru_hole circle
			(at -7.125 3.400001 180)
			(size 1.4732 1.4732)
			(drill 0.9652)
			(layers "*.Cu" "*.Mask")
			(remove_unused_layers no)
			(net "GND")
		)
		(pad "9" thru_hole circle
			(at 7.125 3.400001 180)
			(size 1.4732 1.4732)
			(drill 0.9652)
			(layers "*.Cu" "*.Mask")
			(remove_unused_layers no)
			(net "GND")
		)
		(pad "10" thru_hole rect
			(at 7.125 5.900001 180)
			(size 2.0066 2.0066)
			(drill 1.0414)
			(layers "*.Cu" "*.Mask")
			(remove_unused_layers no)
			(net "GND")
			(padstack
				(mode front_inner_back)
				(layer "Inner"
					(shape circle)
					(size 2.0066 2.0066)
				)
				(layer "B.Cu"
					(shape rect)
					(size 2.0066 2.0066)
				)
			)
		)
		(pad "11" thru_hole circle
			(at -7.125 8.099999 180)
			(size 1.4732 1.4732)
			(drill 0.9652)
			(layers "*.Cu" "*.Mask")
			(remove_unused_layers no)
			(net "GND")
		)
		(pad "12" thru_hole circle
			(at 7.125 8.099999 180)
			(size 1.4732 1.4732)
			(drill 0.9652)
			(layers "*.Cu" "*.Mask")
			(remove_unused_layers no)
			(net "GND")
		)
		(pad "13" thru_hole rect
			(at -7.125 10.900001 180)
			(size 2.0066 2.0066)
			(drill 1.0414)
			(layers "*.Cu" "*.Mask")
			(remove_unused_layers no)
			(net "GND")
			(padstack
				(mode front_inner_back)
				(layer "Inner"
					(shape circle)
					(size 2.0066 2.0066)
				)
				(layer "B.Cu"
					(shape rect)
					(size 2.0066 2.0066)
				)
			)
		)
		(pad "14" thru_hole rect
			(at -1.445001 10.900001 180)
			(size 2.0066 2.0066)
			(drill 1.0414)
			(layers "*.Cu" "*.Mask")
			(remove_unused_layers no)
			(net "GND")
			(padstack
				(mode front_inner_back)
				(layer "Inner"
					(shape circle)
					(size 2.0066 2.0066)
				)
				(layer "B.Cu"
					(shape rect)
					(size 2.0066 2.0066)
				)
			)
		)
		(pad "15" thru_hole rect
			(at 3.955001 10.900001 180)
			(size 2.0066 2.0066)
			(drill 1.0414)
			(layers "*.Cu" "*.Mask")
			(remove_unused_layers no)
			(net "GND")
			(padstack
				(mode front_inner_back)
				(layer "Inner"
					(shape circle)
					(size 2.0066 2.0066)
				)
				(layer "B.Cu"
					(shape rect)
					(size 2.0066 2.0066)
				)
			)
		)
		(pad "16" thru_hole rect
			(at 7.125 15.900001 180)
			(size 2.0066 2.0066)
			(drill 1.0414)
			(layers "*.Cu" "*.Mask")
			(remove_unused_layers no)
			(net "GND")
			(padstack
				(mode front_inner_back)
				(layer "Inner"
					(shape circle)
					(size 2.0066 2.0066)
				)
				(layer "B.Cu"
					(shape rect)
					(size 2.0066 2.0066)
				)
			)
		)
		(pad "17" thru_hole rect
			(at -7.125 20.899999 180)
			(size 2.0066 2.0066)
			(drill 1.0414)
			(layers "*.Cu" "*.Mask")
			(remove_unused_layers no)
			(net "GND")
			(padstack
				(mode front_inner_back)
				(layer "Inner"
					(shape circle)
					(size 2.0066 2.0066)
				)
				(layer "B.Cu"
					(shape rect)
					(size 2.0066 2.0066)
				)
			)
		)
		(pad "18" thru_hole rect
			(at 7.125 25.899999 180)
			(size 2.0066 2.0066)
			(drill 1.0414)
			(layers "*.Cu" "*.Mask")
			(remove_unused_layers no)
			(net "GND")
			(padstack
				(mode front_inner_back)
				(layer "Inner"
					(shape circle)
					(size 2.0066 2.0066)
				)
				(layer "B.Cu"
					(shape rect)
					(size 2.0066 2.0066)
				)
			)
		)
		(pad "19" thru_hole rect
			(at -7.125 30.899999 180)
			(size 2.0066 2.0066)
			(drill 1.0414)
			(layers "*.Cu" "*.Mask")
			(remove_unused_layers no)
			(net "GND")
			(padstack
				(mode front_inner_back)
				(layer "Inner"
					(shape circle)
					(size 2.0066 2.0066)
				)
				(layer "B.Cu"
					(shape rect)
					(size 2.0066 2.0066)
				)
			)
		)
		(pad "20" thru_hole rect
			(at 1.455001 30.899999 180)
			(size 2.0066 2.0066)
			(drill 1.0414)
			(layers "*.Cu" "*.Mask")
			(remove_unused_layers no)
			(net "GND")
			(padstack
				(mode front_inner_back)
				(layer "Inner"
					(shape circle)
					(size 2.0066 2.0066)
				)
				(layer "B.Cu"
					(shape rect)
					(size 2.0066 2.0066)
				)
			)
		)
	)
	(footprint ""
		(layer "F.Cu")
		(at -60.388401 44.869202 -90)
		(property "Reference" "R45"
			(at -4.102202 0.025499 90)
			(unlocked yes)
			(layer "F.SilkS")
			(effects
				(font
					(size 0.762 0.5334)
					(thickness 0.1016)
				)
			)
		)
		(property "Value" ""
			(at 0 0 270)
			(layer "F.Fab")
			(effects
				(font
					(size 1.27 1.27)
				)
			)
		)
		(duplicate_pad_numbers_are_jumpers no)
		(fp_line
			(start 0 -0.381)
			(end 0 0.381)
			(stroke
				(width 0.127)
				(type default)
			)
			(layer "F.SilkS")
		)
		(fp_poly
			(pts
				(xy 1.2556 0.656399) (xy -1.255601 0.656399) (xy -1.255601 -0.6564) (xy 1.2556 -0.6564)
			)
			(stroke
				(width 0)
				(type default)
			)
			(fill no)
			(layer "F.CrtYd")
		)
		(fp_line
			(start -0.800001 0.399999)
			(end 0.800001 0.399999)
			(stroke
				(width 0.1)
				(type default)
			)
			(layer "F.Fab")
		)
		(fp_line
			(start 0.800001 0.399999)
			(end 0.800001 -0.399999)
			(stroke
				(width 0.1)
				(type default)
			)
			(layer "F.Fab")
		)
		(fp_line
			(start -0.800001 -0.399999)
			(end -0.800001 0.399999)
			(stroke
				(width 0.1)
				(type default)
			)
			(layer "F.Fab")
		)
		(fp_line
			(start 0.800001 -0.399999)
			(end -0.800001 -0.399999)
			(stroke
				(width 0.1)
				(type default)
			)
			(layer "F.Fab")
		)
		(pad "1" smd rect
			(at -0.650001 0 270)
			(size 0.7112 0.8128)
			(layers "F.Cu" "F.Mask" "F.Paste")
			(net "P3V3_10G_B2_VCCT")
		)
		(pad "2" smd rect
			(at 0.650001 0 90)
			(size 0.7112 0.8128)
			(layers "F.Cu" "F.Mask" "F.Paste")
			(net "P3V3_B2_QSFP")
		)
	)
)
